FILE_TYPE = CONNECTIVITY;
{Allegro Design Entry HDL 16.6-p007 (v16-6-112F) 10/10/2012}
"PAGE_NUMBER" = 53;
0"NC";
1"M_F_DQS_DN<17:0>";
2"M_F_DQS_DP<17:0>";
3"M_F_DQ<63:0>";
4"M_F_MA<17:0>";
5"M_F_BA<1:0>";
6"M_F_CLK_DP<3:0>";
7"M_F_BG<1:0>";
8"M_F_CS_N<7:0>";
9"M_F_CKE<3:0>";
10"M_F_ODT<3:0>";
11"M_F_ECC<7:0>";
12"M_F_CLK_DN<3:0>";
13"PVTT_DEF\g";
14"PVDDQ_DEF\g";
15"GND\g";
16"GND\g";
17"GND\g";
18"PVPP_DEF\g";
19"PVPP_DEF\g";
20"P12V_NVDIMM_DEF\g";
21"GND\g";
22"M_F_MA<8>";
23"M_F_DQ<32>";
24"M_F_DQ<35>";
25"M_F_DQ<37>";
26"M_F_DQ<38>";
27"M_F_MA<16>";
28"M_F_MA<11>";
29"M_F_MA<10>";
30"M_F_DQ<40>";
31"M_F_VREF";
32"TP_CH_F_DIMM_F0_RFU_1";
33"TP_CH_F_DIMM_F0_RFU_0";
34"TP_CH_F_DIMM_F0_RFU_2";
35"M_F_ACT_N";
36"M_F_ALERT_N";
37"SMB_DDR_DEF_VPP_SCL";
38"SMB_DDR_DEF_VPP_SDA";
39"FM_ADR_COMPLETE_DEF_N";
40"M_DEF_RST_N";
41"FM_DIMM_EVENT_COD_N";
42"M_F_PAR";
43"M_F_CLK_DN<0>";
44"M_F_CLK_DN<1>";
45"M_F_ODT<0>";
46"M_F_ECC<6>";
47"M_F_ECC<1>";
48"M_F_ECC<0>";
49"M_F_ECC<3>";
50"M_F_ECC<2>";
51"M_F_ECC<5>";
52"M_F_ECC<4>";
53"M_F_ECC<7>";
54"M_F_CS_N<0>";
55"M_F_CKE<0>";
56"M_F_ODT<1>";
57"M_F_CKE<1>";
58"M_F_CS_N<1>";
59"M_F_CS_N<2>";
60"M_F_CS_N<3>";
61"M_F_C<2>";
62"M_F_BA<0>";
63"M_F_BG<1>";
64"M_F_BG<0>";
65"M_F_CLK_DP<1>";
66"M_F_CLK_DP<0>";
67"M_F_BA<1>";
68"M_F_MA<2>";
69"M_F_MA<9>";
70"M_F_MA<7>";
71"M_F_MA<6>";
72"M_F_MA<5>";
73"M_F_MA<4>";
74"M_F_MA<3>";
75"M_F_MA<1>";
76"M_F_MA<0>";
77"M_F_DQ<5>";
78"M_F_DQ<2>";
79"M_F_DQ<3>";
80"M_F_DQ<1>";
81"M_F_DQ<0>";
82"M_F_DQ<4>";
83"M_F_DQ<7>";
84"M_F_DQ<6>";
85"M_F_DQ<9>";
86"M_F_DQ<8>";
87"M_F_DQ<10>";
88"M_F_DQ<12>";
89"M_F_DQ<15>";
90"M_F_DQ<11>";
91"M_F_DQ<13>";
92"M_F_DQ<16>";
93"M_F_DQ<14>";
94"M_F_DQ<17>";
95"M_F_DQ<20>";
96"M_F_DQ<23>";
97"M_F_DQ<22>";
98"M_F_DQ<19>";
99"M_F_DQ<18>";
100"M_F_DQ<21>";
101"M_F_DQ<25>";
102"M_F_DQ<27>";
103"M_F_DQ<26>";
104"M_F_DQ<24>";
105"M_F_DQ<31>";
106"M_F_DQ<30>";
107"M_F_DQ<33>";
108"M_F_DQ<29>";
109"M_F_DQ<28>";
110"M_F_DQ<39>";
111"M_F_DQ<34>";
112"M_F_DQ<36>";
113"M_F_DQ<41>";
114"M_F_DQ<43>";
115"M_F_DQ<42>";
116"M_F_DQ<45>";
117"M_F_DQ<44>";
118"M_F_DQ<46>";
119"M_F_DQ<49>";
120"M_F_DQ<48>";
121"M_F_DQ<51>";
122"M_F_DQ<50>";
123"M_F_DQ<53>";
124"M_F_DQ<52>";
125"M_F_DQ<55>";
126"M_F_DQ<47>";
127"M_F_DQ<54>";
128"M_F_MA<15>";
129"M_F_MA<14>";
130"M_F_MA<17>";
131"M_F_MA<13>";
132"M_F_MA<12>";
133"M_F_DQ<62>";
134"M_F_DQ<63>";
135"M_F_DQ<60>";
136"M_F_DQ<59>";
137"M_F_DQ<56>";
138"M_F_DQ<57>";
139"M_F_DQ<58>";
140"M_F_DQ<61>";
141"M_F_DQS_DN<6>";
142"M_F_DQS_DP<5>";
143"M_F_DQS_DN<5>";
144"M_F_DQS_DP<4>";
145"M_F_DQS_DN<4>";
146"M_F_DQS_DP<3>";
147"M_F_DQS_DN<3>";
148"M_F_DQS_DP<2>";
149"M_F_DQS_DN<2>";
150"M_F_DQS_DP<1>";
151"M_F_DQS_DN<1>";
152"M_F_DQS_DP<0>";
153"M_F_DQS_DN<0>";
154"M_F_DQS_DP<9>";
155"M_F_DQS_DN<9>";
156"M_F_DQS_DP<8>";
157"M_F_DQS_DN<8>";
158"M_F_DQS_DP<7>";
159"M_F_DQS_DN<7>";
160"M_F_DQS_DP<6>";
161"M_F_DQS_DP<16>";
162"M_F_DQS_DN<16>";
163"M_F_DQS_DP<15>";
164"M_F_DQS_DN<15>";
165"M_F_DQS_DP<14>";
166"M_F_DQS_DN<14>";
167"M_F_DQS_DP<13>";
168"M_F_DQS_DN<13>";
169"M_F_DQS_DP<12>";
170"M_F_DQS_DN<12>";
171"M_F_DQS_DP<11>";
172"M_F_DQS_DN<11>";
173"M_F_DQS_DP<10>";
174"M_F_DQS_DN<10>";
175"M_F_DQS_DP<17>";
176"M_F_DQS_DN<17>";
%"TAP"
"6","(650,5100)","2","mstr_standard","I10";
;
CDS_LIB"mstr_standard"
BODY_TYPE"PLUMBING"
HDL_TAP"TRUE";
"B \NAC \NWC"2;
"S \NAC"
BN"16"161;
%"TAP"
"6","(-1550,1825)","2","mstr_standard","I100";
;
CDS_LIB"mstr_standard"
BODY_TYPE"PLUMBING"
HDL_TAP"TRUE";
"B \NAC \NWC"3;
"S \NAC"
BN"11"90;
%"TAP"
"6","(-1550,1775)","2","mstr_standard","I101";
;
CDS_LIB"mstr_standard"
BODY_TYPE"PLUMBING"
HDL_TAP"TRUE";
"B \NAC \NWC"3;
"S \NAC"
BN"8"86;
%"TAP"
"6","(-1550,1675)","2","mstr_standard","I102";
;
CDS_LIB"mstr_standard"
BODY_TYPE"PLUMBING"
HDL_TAP"TRUE";
"B \NAC \NWC"3;
"S \NAC"
BN"6"84;
%"TAP"
"6","(-1550,1725)","2","mstr_standard","I103";
;
CDS_LIB"mstr_standard"
BODY_TYPE"PLUMBING"
HDL_TAP"TRUE";
"B \NAC \NWC"3;
"S \NAC"
BN"9"85;
%"TAP"
"6","(-1550,1625)","2","mstr_standard","I104";
;
CDS_LIB"mstr_standard"
BODY_TYPE"PLUMBING"
HDL_TAP"TRUE";
"B \NAC \NWC"3;
"S \NAC"
BN"7"83;
%"TAP"
"6","(-1550,1575)","2","mstr_standard","I105";
;
CDS_LIB"mstr_standard"
BODY_TYPE"PLUMBING"
HDL_TAP"TRUE";
"B \NAC \NWC"3;
"S \NAC"
BN"4"82;
%"TAP"
"6","(-1550,1475)","2","mstr_standard","I106";
;
CDS_LIB"mstr_standard"
BODY_TYPE"PLUMBING"
HDL_TAP"TRUE";
"B \NAC \NWC"3;
"S \NAC"
BN"2"78;
%"TAP"
"6","(-1550,1525)","2","mstr_standard","I107";
;
CDS_LIB"mstr_standard"
BODY_TYPE"PLUMBING"
HDL_TAP"TRUE";
"B \NAC \NWC"3;
"S \NAC"
BN"5"77;
%"TAP"
"6","(-1550,1375)","2","mstr_standard","I108";
;
CDS_LIB"mstr_standard"
BODY_TYPE"PLUMBING"
HDL_TAP"TRUE";
"B \NAC \NWC"3;
"S \NAC"
BN"0"81;
%"TAP"
"6","(-1550,1425)","2","mstr_standard","I109";
;
CDS_LIB"mstr_standard"
BODY_TYPE"PLUMBING"
HDL_TAP"TRUE";
"B \NAC \NWC"3;
"S \NAC"
BN"3"79;
%"TAP"
"6","(650,5000)","2","mstr_standard","I11";
;
CDS_LIB"mstr_standard"
BODY_TYPE"PLUMBING"
HDL_TAP"TRUE";
"B \NAC \NWC"2;
"S \NAC"
BN"15"163;
%"TAP"
"6","(-1550,1325)","2","mstr_standard","I110";
;
CDS_LIB"mstr_standard"
BODY_TYPE"PLUMBING"
HDL_TAP"TRUE";
"B \NAC \NWC"3;
"S \NAC"
BN"1"80;
%"SCONN288_H44441004"
"1","(-2300,2825)","0","mstr_sconn","I111";
;
CDS_SEC"1"
PART_NUMBER"H44441-004"
MATERIAL"SCONN"
LOCATION"J4A1"
PACK_TYPE"PIP"
BOM_COST"MEM"
CDS_LIB"mstr_sconn"
SEC_TYPE"PIP"
SEC"1"
CDS_LOCATION"J4A1"
ROOM"DDR4_CH_F";
"DQ<63>"
$PN"280"133;
"DQ<62>"
$PN"135"134;
"DQ<61>"
$PN"273"135;
"DQ<5>"
$PN"148"82;
"DQ<4>"
$PN"3"77;
"DQ<3>"
$PN"157"78;
"DQ<2>"
$PN"12"79;
"DQ<47>"
$PN"258"118;
"DQ<48>"
$PN"119"119;
"DQ<49>"
$PN"264"120;
"DQ<50>"
$PN"126"121;
"DQ<51>"
$PN"271"122;
"DQ<52>"
$PN"117"123;
"DQ<53>"
$PN"262"124;
"DQ<54>"
$PN"124"125;
"DQ<58>"
$PN"137"136;
"DQ<57>"
$PN"275"137;
"SAVE_N_NC"
$PN"230"39;
"RFU<1>"
$PN"227"32;
"RFU<0>"
$PN"205"33;
"DQ<17>"
$PN"172"92;
"DQ<15>"
$PN"166"93;
"DQ<26>"
$PN"45"102;
"DQ<27>"
$PN"190"103;
"S0_N"
$PN"84"54;
"CKE<0>"
$PN"60"55;
"ODT<1>"
$PN"91"56;
"ODT<0>"
$PN"87"45;
"CB<7>"
$PN"199"46;
"A16_RAS_N"
$PN"82"27;
"A15_CAS_N"
$PN"86"128;
"A14_WE_N"
$PN"228"129;
"A11"
$PN"210"28;
"A10"
$PN"225"29;
"DQ<38>"
$PN"102"110;
"DQ<36>"
$PN"95"25;
"DQ<35>"
$PN"249"111;
"A2"
$PN"216"68;
"ALERT_N"
$PN"208"36;
"ACT_N"
$PN"62"35;
"DQ<0>"
$PN"5"80;
"DQ<1>"
$PN"150"81;
"SA<1>"
$PN"140"16;
"SA<2>"
$PN"238"19;
"VDDSPD"
$PN"284"19;
"SA<0>"
$PN"139"16;
"BA<0>"
$PN"81"62;
"BG<1>"
$PN"207"63;
"BG<0>"
$PN"63"64;
"CK1P"
$PN"218"65;
"VREFCA"
$PN"146"31;
"SDA"
$PN"285"38;
"SCL"
$PN"141"37;
"RFU<2>"
$PN"144"34;
"RESET_N"
$PN"58"40;
"PAR"
$PN"222"42;
"EVENT_N"
$PN"78"41;
"DQ<6>"
$PN"10"83;
"DQ<7>"
$PN"155"84;
"DQ<8>"
$PN"16"85;
"DQ<9>"
$PN"161"86;
"DQ<10>"
$PN"23"90;
"DQ<11>"
$PN"168"87;
"DQ<12>"
$PN"14"91;
"DQ<13>"
$PN"159"88;
"DQ<14>"
$PN"21"89;
"DQ<16>"
$PN"27"94;
"DQ<18>"
$PN"34"98;
"DQ<19>"
$PN"179"99;
"DQ<20>"
$PN"25"100;
"DQ<21>"
$PN"170"95;
"DQ<22>"
$PN"32"96;
"DQ<23>"
$PN"177"97;
"DQ<24>"
$PN"38"101;
"DQ<25>"
$PN"183"104;
"DQ<30>"
$PN"43"105;
"DQ<31>"
$PN"188"106;
"DQ<32>"
$PN"97"107;
"DQ<33>"
$PN"242"23;
"DQ<34>"
$PN"104"24;
"DQ<37>"
$PN"240"112;
"DQ<39>"
$PN"247"26;
"DQ<40>"
$PN"108"113;
"DQ<41>"
$PN"253"30;
"DQ<42>"
$PN"115"114;
"DQ<43>"
$PN"260"115;
"DQ<44>"
$PN"106"116;
"DQ<45>"
$PN"251"117;
"DQ<46>"
$PN"113"126;
"DQ<55>"
$PN"269"127;
"DQ<56>"
$PN"130"138;
"DQ<59>"
$PN"282"139;
"DQ<60>"
$PN"128"140;
"CKE<1>"
$PN"203"57;
"CK0N"
$PN"75"43;
"CB<0>"
$PN"49"47;
"CB<1>"
$PN"194"48;
"CB<2>"
$PN"56"49;
"CB<3>"
$PN"201"50;
"CB<4>"
$PN"47"51;
"CB<5>"
$PN"192"52;
"CB<6>"
$PN"54"53;
"A9"
$PN"66"69;
"A8"
$PN"68"22;
"A7"
$PN"211"70;
"A6"
$PN"69"71;
"A5"
$PN"213"72;
"A4"
$PN"214"73;
"A3"
$PN"71"74;
"A17"
$PN"234"130;
"A13"
$PN"232"131;
"A12"
$PN"65"132;
"A1"
$PN"72"75;
"A0"
$PN"79"76;
"C<2>"
$PN"235"61;
"DQ<28>"
$PN"36"108;
"DQ<29>"
$PN"181"109;
"S1_N"
$PN"89"58;
"S2_N_C<0>"
$PN"93"59;
"S3_N_C<1>"
$PN"237"60;
"CK0P"
$PN"74"66;
"CK1N"
$PN"219"44;
"BA<1>"
$PN"224"67;
%"TAP"
"6","(-3050,4475)","0","mstr_standard","I112";
;
CDS_LIB"mstr_standard"
BODY_TYPE"PLUMBING"
HDL_TAP"TRUE";
"B \NAC \NWC"4;
"S \NAC"
BN"17"130;
%"TAP"
"6","(-3050,4425)","0","mstr_standard","I113";
;
CDS_LIB"mstr_standard"
BODY_TYPE"PLUMBING"
HDL_TAP"TRUE";
"B \NAC \NWC"4;
"S \NAC"
BN"16"27;
%"TAP"
"6","(-3050,4375)","0","mstr_standard","I114";
;
CDS_LIB"mstr_standard"
BODY_TYPE"PLUMBING"
HDL_TAP"TRUE";
"B \NAC \NWC"4;
"S \NAC"
BN"15"128;
%"TAP"
"6","(-3050,4325)","0","mstr_standard","I115";
;
CDS_LIB"mstr_standard"
BODY_TYPE"PLUMBING"
HDL_TAP"TRUE";
"B \NAC \NWC"4;
"S \NAC"
BN"14"129;
%"TAP"
"6","(-3050,4275)","0","mstr_standard","I116";
;
CDS_LIB"mstr_standard"
BODY_TYPE"PLUMBING"
HDL_TAP"TRUE";
"B \NAC \NWC"4;
"S \NAC"
BN"13"131;
%"TAP"
"6","(-3050,4225)","0","mstr_standard","I117";
;
CDS_LIB"mstr_standard"
BODY_TYPE"PLUMBING"
HDL_TAP"TRUE";
"B \NAC \NWC"4;
"S \NAC"
BN"12"132;
%"TAP"
"6","(-3050,4175)","0","mstr_standard","I118";
;
CDS_LIB"mstr_standard"
BODY_TYPE"PLUMBING"
HDL_TAP"TRUE";
"B \NAC \NWC"4;
"S \NAC"
BN"11"28;
%"TAP"
"6","(-3050,4125)","0","mstr_standard","I119";
;
CDS_LIB"mstr_standard"
BODY_TYPE"PLUMBING"
HDL_TAP"TRUE";
"B \NAC \NWC"4;
"S \NAC"
BN"10"29;
%"TAP"
"6","(650,4900)","2","mstr_standard","I12";
;
CDS_LIB"mstr_standard"
BODY_TYPE"PLUMBING"
HDL_TAP"TRUE";
"B \NAC \NWC"2;
"S \NAC"
BN"14"165;
%"TAP"
"6","(-3050,4075)","0","mstr_standard","I120";
;
CDS_LIB"mstr_standard"
BODY_TYPE"PLUMBING"
HDL_TAP"TRUE";
"B \NAC \NWC"4;
"S \NAC"
BN"9"69;
%"TAP"
"6","(-3050,4025)","0","mstr_standard","I121";
;
CDS_LIB"mstr_standard"
BODY_TYPE"PLUMBING"
HDL_TAP"TRUE";
"B \NAC \NWC"4;
"S \NAC"
BN"8"22;
%"TAP"
"6","(-3050,3975)","0","mstr_standard","I122";
;
CDS_LIB"mstr_standard"
BODY_TYPE"PLUMBING"
HDL_TAP"TRUE";
"B \NAC \NWC"4;
"S \NAC"
BN"7"70;
%"TAP"
"6","(-3050,3925)","0","mstr_standard","I123";
;
CDS_LIB"mstr_standard"
BODY_TYPE"PLUMBING"
HDL_TAP"TRUE";
"B \NAC \NWC"4;
"S \NAC"
BN"6"71;
%"TAP"
"6","(-3050,3875)","0","mstr_standard","I124";
;
CDS_LIB"mstr_standard"
BODY_TYPE"PLUMBING"
HDL_TAP"TRUE";
"B \NAC \NWC"4;
"S \NAC"
BN"5"72;
%"TAP"
"6","(-3050,3825)","0","mstr_standard","I125";
;
CDS_LIB"mstr_standard"
BODY_TYPE"PLUMBING"
HDL_TAP"TRUE";
"B \NAC \NWC"4;
"S \NAC"
BN"4"73;
%"TAP"
"6","(-3050,3775)","0","mstr_standard","I126";
;
CDS_LIB"mstr_standard"
BODY_TYPE"PLUMBING"
HDL_TAP"TRUE";
"B \NAC \NWC"4;
"S \NAC"
BN"3"74;
%"TAP"
"6","(-3050,3725)","0","mstr_standard","I127";
;
CDS_LIB"mstr_standard"
BODY_TYPE"PLUMBING"
HDL_TAP"TRUE";
"B \NAC \NWC"4;
"S \NAC"
BN"2"68;
%"TAP"
"6","(-3050,3675)","0","mstr_standard","I128";
;
CDS_LIB"mstr_standard"
BODY_TYPE"PLUMBING"
HDL_TAP"TRUE";
"B \NAC \NWC"4;
"S \NAC"
BN"1"75;
%"TAP"
"6","(-3050,3625)","0","mstr_standard","I129";
;
CDS_LIB"mstr_standard"
BODY_TYPE"PLUMBING"
HDL_TAP"TRUE";
"B \NAC \NWC"4;
"S \NAC"
BN"0"76;
%"TAP"
"6","(650,4800)","2","mstr_standard","I13";
;
CDS_LIB"mstr_standard"
BODY_TYPE"PLUMBING"
HDL_TAP"TRUE";
"B \NAC \NWC"2;
"S \NAC"
BN"13"167;
%"TAP"
"6","(-3050,3525)","0","mstr_standard","I130";
;
CDS_LIB"mstr_standard"
BODY_TYPE"PLUMBING"
HDL_TAP"TRUE";
"B \NAC \NWC"5;
"S \NAC"
BN"1"67;
%"TAP"
"6","(-3050,3475)","0","mstr_standard","I133";
;
CDS_LIB"mstr_standard"
BODY_TYPE"PLUMBING"
HDL_TAP"TRUE";
"B \NAC \NWC"5;
"S \NAC"
BN"0"62;
%"TAP"
"6","(-3050,3425)","0","mstr_standard","I134";
;
CDS_LIB"mstr_standard"
BODY_TYPE"PLUMBING"
HDL_TAP"TRUE";
"B \NAC \NWC"7;
"S \NAC"
BN"1"63;
%"TAP"
"6","(-3050,3375)","0","mstr_standard","I135";
;
CDS_LIB"mstr_standard"
BODY_TYPE"PLUMBING"
HDL_TAP"TRUE";
"B \NAC \NWC"7;
"S \NAC"
BN"0"64;
%"TAP"
"6","(-3050,2375)","0","mstr_standard","I138";
;
CDS_LIB"mstr_standard"
BODY_TYPE"PLUMBING"
HDL_TAP"TRUE";
"B \NAC \NWC"11;
"S \NAC"
BN"7"53;
%"TAP"
"6","(-3050,2425)","0","mstr_standard","I139";
;
CDS_LIB"mstr_standard"
BODY_TYPE"PLUMBING"
HDL_TAP"TRUE";
"B \NAC \NWC"11;
"S \NAC"
BN"6"46;
%"TAP"
"6","(650,4600)","2","mstr_standard","I14";
;
CDS_LIB"mstr_standard"
BODY_TYPE"PLUMBING"
HDL_TAP"TRUE";
"B \NAC \NWC"2;
"S \NAC"
BN"11"171;
%"TAP"
"6","(-3050,2325)","0","mstr_standard","I140";
;
CDS_LIB"mstr_standard"
BODY_TYPE"PLUMBING"
HDL_TAP"TRUE";
"B \NAC \NWC"11;
"S \NAC"
BN"4"52;
%"TAP"
"6","(-3050,2275)","0","mstr_standard","I141";
;
CDS_LIB"mstr_standard"
BODY_TYPE"PLUMBING"
HDL_TAP"TRUE";
"B \NAC \NWC"11;
"S \NAC"
BN"5"51;
%"TAP"
"6","(-3050,2225)","0","mstr_standard","I142";
;
CDS_LIB"mstr_standard"
BODY_TYPE"PLUMBING"
HDL_TAP"TRUE";
"B \NAC \NWC"11;
"S \NAC"
BN"2"50;
%"TAP"
"6","(-3050,2175)","0","mstr_standard","I143";
;
CDS_LIB"mstr_standard"
BODY_TYPE"PLUMBING"
HDL_TAP"TRUE";
"B \NAC \NWC"11;
"S \NAC"
BN"3"49;
%"TAP"
"6","(-3050,2125)","0","mstr_standard","I144";
;
CDS_LIB"mstr_standard"
BODY_TYPE"PLUMBING"
HDL_TAP"TRUE";
"B \NAC \NWC"11;
"S \NAC"
BN"0"48;
%"TAP"
"6","(-3050,2075)","0","mstr_standard","I145";
;
CDS_LIB"mstr_standard"
BODY_TYPE"PLUMBING"
HDL_TAP"TRUE";
"B \NAC \NWC"11;
"S \NAC"
BN"1"47;
%"TAP"
"6","(650,4700)","2","mstr_standard","I15";
;
CDS_LIB"mstr_standard"
BODY_TYPE"PLUMBING"
HDL_TAP"TRUE";
"B \NAC \NWC"2;
"S \NAC"
BN"12"169;
%"TAP"
"6","(-3050,3275)","0","mstr_standard","I152";
;
CDS_LIB"mstr_standard"
BODY_TYPE"PLUMBING"
HDL_TAP"TRUE";
"B \NAC \NWC"6;
"S \NAC"
BN"1"65;
%"TAP"
"6","(-3050,3175)","0","mstr_standard","I153";
;
CDS_LIB"mstr_standard"
BODY_TYPE"PLUMBING"
HDL_TAP"TRUE";
"B \NAC \NWC"6;
"S \NAC"
BN"0"66;
%"TAP"
"6","(-3250,3225)","0","mstr_standard","I154";
;
CDS_LIB"mstr_standard"
BODY_TYPE"PLUMBING"
HDL_TAP"TRUE";
"B \NAC \NWC"12;
"S \NAC"
BN"1"44;
%"TAP"
"6","(-3250,3125)","0","mstr_standard","I155";
;
CDS_LIB"mstr_standard"
BODY_TYPE"PLUMBING"
HDL_TAP"TRUE";
"B \NAC \NWC"12;
"S \NAC"
BN"0"43;
%"TAP"
"6","(-3050,2975)","0","mstr_standard","I158";
;
CDS_LIB"mstr_standard"
BODY_TYPE"PLUMBING"
HDL_TAP"TRUE";
"B \NAC \NWC"8;
"S \NAC"
BN"3"60;
%"TAP"
"6","(-3050,2925)","0","mstr_standard","I159";
;
CDS_LIB"mstr_standard"
BODY_TYPE"PLUMBING"
HDL_TAP"TRUE";
"B \NAC \NWC"8;
"S \NAC"
BN"2"59;
%"TAP"
"6","(-3050,2875)","0","mstr_standard","I160";
;
CDS_LIB"mstr_standard"
BODY_TYPE"PLUMBING"
HDL_TAP"TRUE";
"B \NAC \NWC"8;
"S \NAC"
BN"1"58;
%"TAP"
"6","(-3050,2825)","0","mstr_standard","I161";
;
CDS_LIB"mstr_standard"
BODY_TYPE"PLUMBING"
HDL_TAP"TRUE";
"B \NAC \NWC"8;
"S \NAC"
BN"0"54;
%"TAP"
"6","(-3050,2725)","0","mstr_standard","I162";
;
CDS_LIB"mstr_standard"
BODY_TYPE"PLUMBING"
HDL_TAP"TRUE";
"B \NAC \NWC"9;
"S \NAC"
BN"1"57;
%"TAP"
"6","(-3050,2675)","0","mstr_standard","I163";
;
CDS_LIB"mstr_standard"
BODY_TYPE"PLUMBING"
HDL_TAP"TRUE";
"B \NAC \NWC"9;
"S \NAC"
BN"0"55;
%"TAP"
"6","(-3050,2575)","0","mstr_standard","I164";
;
CDS_LIB"mstr_standard"
BODY_TYPE"PLUMBING"
HDL_TAP"TRUE";
"B \NAC \NWC"10;
"S \NAC"
BN"1"56;
%"TAP"
"6","(-3050,2525)","0","mstr_standard","I165";
;
CDS_LIB"mstr_standard"
BODY_TYPE"PLUMBING"
HDL_TAP"TRUE";
"B \NAC \NWC"10;
"S \NAC"
BN"0"45;
%"PVTT_DEF"
"1","(-1100,2750)","0","mstr_symbols","I17";
;
VOLTAGE"0.6V"
BOM_COST"MEM"
CDS_LIB"mstr_symbols"
BODY_TYPE"PLUMBING"
ROOM"DDR4_CH_C"
HDL_POWER"PVTT_DEF";
"G\NAC"13;
%"SCONN288_H44441004"
"4","(-250,2050)","0","mstr_sconn","I171";
;
CDS_SEC"4"
LOCATION"J4A1"
PART_NUMBER"H44441-004"
MATERIAL"SCONN"
PACK_TYPE"PIP"
BOM_COST"MEM"
CDS_LIB"mstr_sconn"
SEC_TYPE"PIP"
SEC"4"
CDS_LOCATION"J4A1"
ROOM"DDR4_CH_F";
"VPP<4>"
$PN"142"18;
"VTT<1>"
$PN"77"13;
"VPP<0>"
$PN"287"18;
"VPP<1>"
$PN"286"18;
"VPP<2>"
$PN"288"18;
"VPP<3>"
$PN"143"18;
"VDD<1>"
$PN"233"14;
"VDD<2>"
$PN"231"14;
"VDD<3>"
$PN"229"14;
"VDD<4>"
$PN"226"14;
"VDD<5>"
$PN"223"14;
"VDD<7>"
$PN"217"14;
"VDD<8>"
$PN"215"14;
"VDD<9>"
$PN"212"14;
"VDD<11>"
$PN"206"14;
"VDD<12>"
$PN"204"14;
"VDD<14>"
$PN"90"14;
"VDD<15>"
$PN"88"14;
"VDD<17>"
$PN"83"14;
"VDD<18>"
$PN"80"14;
"VDD<20>"
$PN"73"14;
"VDD<21>"
$PN"70"14;
"VDD<22>"
$PN"67"14;
"VDD<24>"
$PN"61"14;
"12V<0>"
$PN"145"20;
"12V<1>"
$PN"1"20;
"VTT<0>"
$PN"221"13;
"VDD<25>"
$PN"59"14;
"VDD<23>"
$PN"64"14;
"VDD<19>"
$PN"76"14;
"VDD<16>"
$PN"85"14;
"VDD<13>"
$PN"92"14;
"VDD<10>"
$PN"209"14;
"VDD<6>"
$PN"220"14;
"VDD<0>"
$PN"236"14;
%"PVDDQ_DEF"
"1","(-1275,2600)","0","mstr_symbols","I172";
;
VOLTAGE"1.2V"
BOM_COST"MEM"
CDS_LIB"mstr_symbols"
BODY_TYPE"PLUMBING"
ROOM"DDR4_CH_C"
HDL_POWER"PVDDQ_DEF";
"G\NAC"14;
%"GND"
"1","(2450,1100)","2","mstr_symbols","I173";
;
VOLTAGE"0"
BOM_COST"MEM"
SIZE"1B"
CDS_LIB"mstr_symbols"
BODY_TYPE"PLUMBING"
ROOM"DDR4_CH_C"
HDL_POWER"GND";
"A\NAC"15;
%"GND"
"1","(-5050,1475)","2","mstr_symbols","I175";
;
VOLTAGE"0"
BOM_COST"MEM"
CDS_LIB"mstr_symbols"
SIZE"1B"
BODY_TYPE"PLUMBING"
ROOM"DDR4_CH_C"
HDL_POWER"GND";
"A\NAC"16;
%"CAP_A"
"1","(-4500,1125)","2","dev_discrete","I178";
;
CDS_SEC"1"
LOCATION"C6L1"
PART_NUMBER"A36096-045"
VALUE"0.01UF"
TOLERANCE"10%"
MATERIAL"X7R"
VOLTAGE"25V"
PACK_TYPE"0402V"
CDS_LOCATION"C6L1"
BOM_COST"MEM"
CDS_LIB"dev_discrete"
ROOM"DDR4_CH_F"
SEC"1"
SEC_TYPE"0402V";
"B"
$PN"2"17;
"A"
$PN"1"31;
%"GND"
"1","(-4500,875)","0","mstr_symbols","I179";
;
VOLTAGE"0"
BOM_COST"MEM"
SIZE"1B"
CDS_LIB"mstr_symbols"
BODY_TYPE"PLUMBING"
ROOM"DDR4_CH_C"
HDL_POWER"GND";
"A\NAC"17;
%"PVPP_DEF"
"1","(-950,3050)","0","mstr_symbols","I180";
;
VOLTAGE"2.5V"
BOM_COST"MEM"
CDS_LIB"mstr_symbols"
BODY_TYPE"PLUMBING"
ROOM"DDR4_CH_C"
HDL_POWER"PVPP_DEF";
"G\NAC"18;
%"PVPP_DEF"
"1","(-5050,1825)","0","mstr_symbols","I181";
;
VOLTAGE"2.5V"
BOM_COST"MEM"
CDS_LIB"mstr_symbols"
BODY_TYPE"PLUMBING"
ROOM"DDR4_CH_C"
HDL_POWER"PVPP_DEF";
"G\NAC"19;
%"TAP"
"6","(850,4550)","2","mstr_standard","I19";
;
CDS_LIB"mstr_standard"
BODY_TYPE"PLUMBING"
HDL_TAP"TRUE";
"B \NAC \NWC"1;
"S \NAC"
BN"11"172;
%"P12V_NVDIMM_DEF"
"1","(450,3125)","0","mstr_symbols","I195";
;
VOLTAGE"12.0"
CDS_LIB"mstr_symbols"
BODY_TYPE"PLUMBING"
HDL_POWER"P12V_NVDIMM_DEF";
"G\NAC"20;
%"TAP"
"6","(850,4450)","2","mstr_standard","I20";
;
CDS_LIB"mstr_standard"
BODY_TYPE"PLUMBING"
HDL_TAP"TRUE";
"B \NAC \NWC"1;
"S \NAC"
BN"10"174;
%"TAP"
"6","(850,4350)","2","mstr_standard","I21";
;
CDS_LIB"mstr_standard"
BODY_TYPE"PLUMBING"
HDL_TAP"TRUE";
"B \NAC \NWC"1;
"S \NAC"
BN"9"155;
%"TAP"
"6","(850,4250)","2","mstr_standard","I22";
;
CDS_LIB"mstr_standard"
BODY_TYPE"PLUMBING"
HDL_TAP"TRUE";
"B \NAC \NWC"1;
"S \NAC"
BN"8"157;
%"TAP"
"6","(850,4150)","2","mstr_standard","I23";
;
CDS_LIB"mstr_standard"
BODY_TYPE"PLUMBING"
HDL_TAP"TRUE";
"B \NAC \NWC"1;
"S \NAC"
BN"7"159;
%"TAP"
"6","(650,4400)","2","mstr_standard","I24";
;
CDS_LIB"mstr_standard"
BODY_TYPE"PLUMBING"
HDL_TAP"TRUE";
"B \NAC \NWC"2;
"S \NAC"
BN"9"154;
%"TAP"
"6","(650,4500)","2","mstr_standard","I25";
;
CDS_LIB"mstr_standard"
BODY_TYPE"PLUMBING"
HDL_TAP"TRUE";
"B \NAC \NWC"2;
"S \NAC"
BN"10"173;
%"TAP"
"6","(650,4300)","2","mstr_standard","I26";
;
CDS_LIB"mstr_standard"
BODY_TYPE"PLUMBING"
HDL_TAP"TRUE";
"B \NAC \NWC"2;
"S \NAC"
BN"8"156;
%"TAP"
"6","(650,4100)","2","mstr_standard","I27";
;
CDS_LIB"mstr_standard"
BODY_TYPE"PLUMBING"
HDL_TAP"TRUE";
"B \NAC \NWC"2;
"S \NAC"
BN"6"160;
%"TAP"
"6","(650,4200)","2","mstr_standard","I28";
;
CDS_LIB"mstr_standard"
BODY_TYPE"PLUMBING"
HDL_TAP"TRUE";
"B \NAC \NWC"2;
"S \NAC"
BN"7"158;
%"TAP"
"6","(850,4050)","2","mstr_standard","I29";
;
CDS_LIB"mstr_standard"
BODY_TYPE"PLUMBING"
HDL_TAP"TRUE";
"B \NAC \NWC"1;
"S \NAC"
BN"6"141;
%"TAP"
"6","(850,5150)","2","mstr_standard","I3";
;
CDS_LIB"mstr_standard"
BODY_TYPE"PLUMBING"
HDL_TAP"TRUE";
"B \NAC \NWC"1;
"S \NAC"
BN"17"176;
%"TAP"
"6","(850,3950)","2","mstr_standard","I30";
;
CDS_LIB"mstr_standard"
BODY_TYPE"PLUMBING"
HDL_TAP"TRUE";
"B \NAC \NWC"1;
"S \NAC"
BN"5"143;
%"TAP"
"6","(850,3850)","2","mstr_standard","I31";
;
CDS_LIB"mstr_standard"
BODY_TYPE"PLUMBING"
HDL_TAP"TRUE";
"B \NAC \NWC"1;
"S \NAC"
BN"4"145;
%"TAP"
"6","(850,3750)","2","mstr_standard","I32";
;
CDS_LIB"mstr_standard"
BODY_TYPE"PLUMBING"
HDL_TAP"TRUE";
"B \NAC \NWC"1;
"S \NAC"
BN"3"147;
%"TAP"
"6","(850,3650)","2","mstr_standard","I33";
;
CDS_LIB"mstr_standard"
BODY_TYPE"PLUMBING"
HDL_TAP"TRUE";
"B \NAC \NWC"1;
"S \NAC"
BN"2"149;
%"TAP"
"6","(650,3900)","2","mstr_standard","I34";
;
CDS_LIB"mstr_standard"
BODY_TYPE"PLUMBING"
HDL_TAP"TRUE";
"B \NAC \NWC"2;
"S \NAC"
BN"4"144;
%"TAP"
"6","(650,4000)","2","mstr_standard","I35";
;
CDS_LIB"mstr_standard"
BODY_TYPE"PLUMBING"
HDL_TAP"TRUE";
"B \NAC \NWC"2;
"S \NAC"
BN"5"142;
%"TAP"
"6","(650,3800)","2","mstr_standard","I36";
;
CDS_LIB"mstr_standard"
BODY_TYPE"PLUMBING"
HDL_TAP"TRUE";
"B \NAC \NWC"2;
"S \NAC"
BN"3"146;
%"TAP"
"6","(650,3700)","2","mstr_standard","I37";
;
CDS_LIB"mstr_standard"
BODY_TYPE"PLUMBING"
HDL_TAP"TRUE";
"B \NAC \NWC"2;
"S \NAC"
BN"2"148;
%"TAP"
"6","(650,3600)","2","mstr_standard","I38";
;
CDS_LIB"mstr_standard"
BODY_TYPE"PLUMBING"
HDL_TAP"TRUE";
"B \NAC \NWC"2;
"S \NAC"
BN"1"150;
%"TAP"
"6","(850,3450)","2","mstr_standard","I39";
;
CDS_LIB"mstr_standard"
BODY_TYPE"PLUMBING"
HDL_TAP"TRUE";
"B \NAC \NWC"1;
"S \NAC"
BN"0"153;
%"TAP"
"6","(650,5200)","2","mstr_standard","I4";
;
CDS_LIB"mstr_standard"
BODY_TYPE"PLUMBING"
HDL_TAP"TRUE";
"B \NAC \NWC"2;
"S \NAC"
BN"17"175;
%"TAP"
"6","(850,3550)","2","mstr_standard","I40";
;
CDS_LIB"mstr_standard"
BODY_TYPE"PLUMBING"
HDL_TAP"TRUE";
"B \NAC \NWC"1;
"S \NAC"
BN"1"151;
%"TAP"
"6","(650,3500)","2","mstr_standard","I41";
;
CDS_LIB"mstr_standard"
BODY_TYPE"PLUMBING"
HDL_TAP"TRUE";
"B \NAC \NWC"2;
"S \NAC"
BN"0"152;
%"SCONN288_H44441004"
"3","(1750,2400)","0","mstr_sconn","I43";
;
CDS_SEC"3"
LOCATION"J4A1"
PART_NUMBER"H44441-004"
MATERIAL"SCONN"
PACK_TYPE"PIP"
BOM_COST"MEM"
CDS_LIB"mstr_sconn"
SEC_TYPE"PIP"
SEC"3"
CDS_LOCATION"J4A1"
ROOM"DDR4_CH_F";
"VSS<93>"
$PN"2"21;
"VSS<92>"
$PN"4"21;
"VSS<91>"
$PN"6"21;
"VSS<90>"
$PN"9"21;
"VSS<89>"
$PN"11"21;
"VSS<88>"
$PN"13"21;
"VSS<0>"
$PN"283"15;
"VSS<1>"
$PN"281"15;
"VSS<2>"
$PN"279"15;
"VSS<3>"
$PN"276"15;
"VSS<4>"
$PN"274"15;
"VSS<5>"
$PN"272"15;
"VSS<6>"
$PN"270"15;
"VSS<7>"
$PN"268"15;
"VSS<8>"
$PN"265"15;
"VSS<9>"
$PN"263"15;
"VSS<10>"
$PN"261"15;
"VSS<11>"
$PN"259"15;
"VSS<12>"
$PN"257"15;
"VSS<13>"
$PN"254"15;
"VSS<14>"
$PN"252"15;
"VSS<15>"
$PN"250"15;
"VSS<16>"
$PN"248"15;
"VSS<17>"
$PN"246"15;
"VSS<18>"
$PN"243"15;
"VSS<19>"
$PN"241"15;
"VSS<20>"
$PN"239"15;
"VSS<21>"
$PN"202"15;
"VSS<22>"
$PN"200"15;
"VSS<23>"
$PN"198"15;
"VSS<24>"
$PN"195"15;
"VSS<25>"
$PN"193"15;
"VSS<26>"
$PN"191"15;
"VSS<27>"
$PN"189"15;
"VSS<28>"
$PN"187"15;
"VSS<29>"
$PN"184"15;
"VSS<30>"
$PN"182"15;
"VSS<31>"
$PN"180"15;
"VSS<32>"
$PN"178"15;
"VSS<33>"
$PN"176"15;
"VSS<34>"
$PN"173"15;
"VSS<35>"
$PN"171"15;
"VSS<36>"
$PN"169"15;
"VSS<37>"
$PN"167"15;
"VSS<38>"
$PN"165"15;
"VSS<39>"
$PN"162"15;
"VSS<40>"
$PN"160"15;
"VSS<41>"
$PN"158"15;
"VSS<42>"
$PN"156"15;
"VSS<43>"
$PN"154"15;
"VSS<44>"
$PN"151"15;
"VSS<47>"
$PN"138"21;
"VSS<48>"
$PN"136"21;
"VSS<49>"
$PN"134"21;
"VSS<50>"
$PN"131"21;
"VSS<51>"
$PN"129"21;
"VSS<52>"
$PN"127"21;
"VSS<53>"
$PN"125"21;
"VSS<54>"
$PN"123"21;
"VSS<55>"
$PN"120"21;
"VSS<56>"
$PN"118"21;
"VSS<57>"
$PN"116"21;
"VSS<58>"
$PN"114"21;
"VSS<59>"
$PN"112"21;
"VSS<60>"
$PN"109"21;
"VSS<61>"
$PN"107"21;
"VSS<62>"
$PN"105"21;
"VSS<63>"
$PN"103"21;
"VSS<64>"
$PN"101"21;
"VSS<65>"
$PN"98"21;
"VSS<66>"
$PN"96"21;
"VSS<67>"
$PN"94"21;
"VSS<68>"
$PN"57"21;
"VSS<69>"
$PN"55"21;
"VSS<70>"
$PN"53"21;
"VSS<71>"
$PN"50"21;
"VSS<72>"
$PN"48"21;
"VSS<73>"
$PN"46"21;
"VSS<74>"
$PN"44"21;
"VSS<75>"
$PN"42"21;
"VSS<76>"
$PN"39"21;
"VSS<77>"
$PN"37"21;
"VSS<78>"
$PN"35"21;
"VSS<79>"
$PN"33"21;
"VSS<80>"
$PN"31"21;
"VSS<81>"
$PN"28"21;
"VSS<82>"
$PN"26"21;
"VSS<83>"
$PN"24"21;
"VSS<84>"
$PN"22"21;
"VSS<85>"
$PN"20"21;
"VSS<86>"
$PN"17"21;
"VSS<87>"
$PN"15"21;
"VSS<45>"
$PN"149"15;
"VSS<46>"
$PN"147"15;
%"GND"
"1","(1050,1075)","2","mstr_symbols","I44";
;
VOLTAGE"0"
BOM_COST"MEM"
SIZE"1B"
CDS_LIB"mstr_symbols"
BODY_TYPE"PLUMBING"
ROOM"DDR4_CH_C"
HDL_POWER"GND";
"A\NAC"21;
%"TAP"
"6","(-1550,4475)","2","mstr_standard","I46";
;
CDS_LIB"mstr_standard"
BODY_TYPE"PLUMBING"
HDL_TAP"TRUE";
"B \NAC \NWC"3;
"S \NAC"
BN"62"133;
%"TAP"
"6","(-1550,4425)","2","mstr_standard","I47";
;
CDS_LIB"mstr_standard"
BODY_TYPE"PLUMBING"
HDL_TAP"TRUE";
"B \NAC \NWC"3;
"S \NAC"
BN"63"134;
%"TAP"
"6","(-1550,4325)","2","mstr_standard","I48";
;
CDS_LIB"mstr_standard"
BODY_TYPE"PLUMBING"
HDL_TAP"TRUE";
"B \NAC \NWC"3;
"S \NAC"
BN"61"140;
%"TAP"
"6","(-1550,4375)","2","mstr_standard","I49";
;
CDS_LIB"mstr_standard"
BODY_TYPE"PLUMBING"
HDL_TAP"TRUE";
"B \NAC \NWC"3;
"S \NAC"
BN"60"135;
%"TAP"
"6","(850,5050)","2","mstr_standard","I5";
;
CDS_LIB"mstr_standard"
BODY_TYPE"PLUMBING"
HDL_TAP"TRUE";
"B \NAC \NWC"1;
"S \NAC"
BN"16"162;
%"TAP"
"6","(-1550,4275)","2","mstr_standard","I50";
;
CDS_LIB"mstr_standard"
BODY_TYPE"PLUMBING"
HDL_TAP"TRUE";
"B \NAC \NWC"3;
"S \NAC"
BN"58"139;
%"TAP"
"6","(-1550,4175)","2","mstr_standard","I51";
;
CDS_LIB"mstr_standard"
BODY_TYPE"PLUMBING"
HDL_TAP"TRUE";
"B \NAC \NWC"3;
"S \NAC"
BN"56"137;
%"TAP"
"6","(-1550,4225)","2","mstr_standard","I52";
;
CDS_LIB"mstr_standard"
BODY_TYPE"PLUMBING"
HDL_TAP"TRUE";
"B \NAC \NWC"3;
"S \NAC"
BN"59"136;
%"TAP"
"6","(-1550,4125)","2","mstr_standard","I53";
;
CDS_LIB"mstr_standard"
BODY_TYPE"PLUMBING"
HDL_TAP"TRUE";
"B \NAC \NWC"3;
"S \NAC"
BN"57"138;
%"TAP"
"6","(-1550,4075)","2","mstr_standard","I54";
;
CDS_LIB"mstr_standard"
BODY_TYPE"PLUMBING"
HDL_TAP"TRUE";
"B \NAC \NWC"3;
"S \NAC"
BN"54"127;
%"TAP"
"6","(-1550,3975)","2","mstr_standard","I55";
;
CDS_LIB"mstr_standard"
BODY_TYPE"PLUMBING"
HDL_TAP"TRUE";
"B \NAC \NWC"3;
"S \NAC"
BN"52"124;
%"TAP"
"6","(-1550,4025)","2","mstr_standard","I56";
;
CDS_LIB"mstr_standard"
BODY_TYPE"PLUMBING"
HDL_TAP"TRUE";
"B \NAC \NWC"3;
"S \NAC"
BN"55"125;
%"TAP"
"6","(-1550,3925)","2","mstr_standard","I57";
;
CDS_LIB"mstr_standard"
BODY_TYPE"PLUMBING"
HDL_TAP"TRUE";
"B \NAC \NWC"3;
"S \NAC"
BN"53"123;
%"TAP"
"6","(-1550,3875)","2","mstr_standard","I58";
;
CDS_LIB"mstr_standard"
BODY_TYPE"PLUMBING"
HDL_TAP"TRUE";
"B \NAC \NWC"3;
"S \NAC"
BN"50"122;
%"TAP"
"6","(-1550,3825)","2","mstr_standard","I59";
;
CDS_LIB"mstr_standard"
BODY_TYPE"PLUMBING"
HDL_TAP"TRUE";
"B \NAC \NWC"3;
"S \NAC"
BN"51"121;
%"TAP"
"6","(850,4950)","2","mstr_standard","I6";
;
CDS_LIB"mstr_standard"
BODY_TYPE"PLUMBING"
HDL_TAP"TRUE";
"B \NAC \NWC"1;
"S \NAC"
BN"15"164;
%"TAP"
"6","(-1550,3775)","2","mstr_standard","I60";
;
CDS_LIB"mstr_standard"
BODY_TYPE"PLUMBING"
HDL_TAP"TRUE";
"B \NAC \NWC"3;
"S \NAC"
BN"48"120;
%"TAP"
"6","(-1550,3675)","2","mstr_standard","I61";
;
CDS_LIB"mstr_standard"
BODY_TYPE"PLUMBING"
HDL_TAP"TRUE";
"B \NAC \NWC"3;
"S \NAC"
BN"46"118;
%"TAP"
"6","(-1550,3725)","2","mstr_standard","I62";
;
CDS_LIB"mstr_standard"
BODY_TYPE"PLUMBING"
HDL_TAP"TRUE";
"B \NAC \NWC"3;
"S \NAC"
BN"49"119;
%"TAP"
"6","(-1550,3625)","2","mstr_standard","I63";
;
CDS_LIB"mstr_standard"
BODY_TYPE"PLUMBING"
HDL_TAP"TRUE";
"B \NAC \NWC"3;
"S \NAC"
BN"47"126;
%"TAP"
"6","(-1550,3575)","2","mstr_standard","I64";
;
CDS_LIB"mstr_standard"
BODY_TYPE"PLUMBING"
HDL_TAP"TRUE";
"B \NAC \NWC"3;
"S \NAC"
BN"44"117;
%"TAP"
"6","(-1550,3525)","2","mstr_standard","I65";
;
CDS_LIB"mstr_standard"
BODY_TYPE"PLUMBING"
HDL_TAP"TRUE";
"B \NAC \NWC"3;
"S \NAC"
BN"45"116;
%"SCONN288_H44441004"
"2","(-50,4350)","0","mstr_sconn","I66";
;
CDS_SEC"2"
LOCATION"J4A1"
MATERIAL"SCONN"
PART_NUMBER"H44441-004"
PACK_TYPE"PIP"
BOM_COST"MEM"
CDS_LIB"mstr_sconn"
SEC_TYPE"PIP"
SEC"2"
CDS_LOCATION"J4A1"
ROOM"DDR4_CH_F";
"DQS17P"
$PN"51"175;
"DQS9P"
$PN"7"154;
"DQS9N"
$PN"8"155;
"DQS8P"
$PN"197"156;
"DQS8N"
$PN"196"157;
"DQS7P"
$PN"278"158;
"DQS7N"
$PN"277"159;
"DQS6P"
$PN"267"160;
"DQS6N"
$PN"266"141;
"DQS5P"
$PN"256"142;
"DQS5N"
$PN"255"143;
"DQS4P"
$PN"245"144;
"DQS4N"
$PN"244"145;
"DQS3P"
$PN"186"146;
"DQS3N"
$PN"185"147;
"DQS2P"
$PN"175"148;
"DQS2N"
$PN"174"149;
"DQS1P"
$PN"164"150;
"DQS1N"
$PN"163"151;
"DQS17N"
$PN"52"176;
"DQS16P"
$PN"132"161;
"DQS16N"
$PN"133"162;
"DQS15P"
$PN"121"163;
"DQS15N"
$PN"122"164;
"DQS14P"
$PN"110"165;
"DQS14N"
$PN"111"166;
"DQS13P"
$PN"99"167;
"DQS13N"
$PN"100"168;
"DQS12P"
$PN"40"169;
"DQS12N"
$PN"41"170;
"DQS11P"
$PN"29"171;
"DQS11N"
$PN"30"172;
"DQS10P"
$PN"18"173;
"DQS10N"
$PN"19"174;
"DQS0P"
$PN"153"152;
"DQS0N"
$PN"152"153;
%"TAP"
"6","(-1550,3475)","2","mstr_standard","I67";
;
CDS_LIB"mstr_standard"
BODY_TYPE"PLUMBING"
HDL_TAP"TRUE";
"B \NAC \NWC"3;
"S \NAC"
BN"42"115;
%"TAP"
"6","(-1550,3425)","2","mstr_standard","I68";
;
CDS_LIB"mstr_standard"
BODY_TYPE"PLUMBING"
HDL_TAP"TRUE";
"B \NAC \NWC"3;
"S \NAC"
BN"43"114;
%"TAP"
"6","(-1550,3325)","2","mstr_standard","I69";
;
CDS_LIB"mstr_standard"
BODY_TYPE"PLUMBING"
HDL_TAP"TRUE";
"B \NAC \NWC"3;
"S \NAC"
BN"41"113;
%"TAP"
"6","(850,4750)","2","mstr_standard","I7";
;
CDS_LIB"mstr_standard"
BODY_TYPE"PLUMBING"
HDL_TAP"TRUE";
"B \NAC \NWC"1;
"S \NAC"
BN"13"168;
%"TAP"
"6","(-1550,3275)","2","mstr_standard","I70";
;
CDS_LIB"mstr_standard"
BODY_TYPE"PLUMBING"
HDL_TAP"TRUE";
"B \NAC \NWC"3;
"S \NAC"
BN"38"26;
%"TAP"
"6","(-1550,3375)","2","mstr_standard","I71";
;
CDS_LIB"mstr_standard"
BODY_TYPE"PLUMBING"
HDL_TAP"TRUE";
"B \NAC \NWC"3;
"S \NAC"
BN"40"30;
%"TAP"
"6","(-1550,3225)","2","mstr_standard","I72";
;
CDS_LIB"mstr_standard"
BODY_TYPE"PLUMBING"
HDL_TAP"TRUE";
"B \NAC \NWC"3;
"S \NAC"
BN"39"110;
%"TAP"
"6","(-1550,3175)","2","mstr_standard","I73";
;
CDS_LIB"mstr_standard"
BODY_TYPE"PLUMBING"
HDL_TAP"TRUE";
"B \NAC \NWC"3;
"S \NAC"
BN"36"112;
%"TAP"
"6","(-1550,3125)","2","mstr_standard","I74";
;
CDS_LIB"mstr_standard"
BODY_TYPE"PLUMBING"
HDL_TAP"TRUE";
"B \NAC \NWC"3;
"S \NAC"
BN"37"25;
%"TAP"
"6","(-1550,3025)","2","mstr_standard","I75";
;
CDS_LIB"mstr_standard"
BODY_TYPE"PLUMBING"
HDL_TAP"TRUE";
"B \NAC \NWC"3;
"S \NAC"
BN"35"24;
%"TAP"
"6","(-1550,3075)","2","mstr_standard","I76";
;
CDS_LIB"mstr_standard"
BODY_TYPE"PLUMBING"
HDL_TAP"TRUE";
"B \NAC \NWC"3;
"S \NAC"
BN"34"111;
%"TAP"
"6","(-1550,2975)","2","mstr_standard","I77";
;
CDS_LIB"mstr_standard"
BODY_TYPE"PLUMBING"
HDL_TAP"TRUE";
"B \NAC \NWC"3;
"S \NAC"
BN"32"23;
%"TAP"
"6","(-1550,2925)","2","mstr_standard","I78";
;
CDS_LIB"mstr_standard"
BODY_TYPE"PLUMBING"
HDL_TAP"TRUE";
"B \NAC \NWC"3;
"S \NAC"
BN"33"107;
%"TAP"
"6","(-1550,2775)","2","mstr_standard","I79";
;
CDS_LIB"mstr_standard"
BODY_TYPE"PLUMBING"
HDL_TAP"TRUE";
"B \NAC \NWC"3;
"S \NAC"
BN"28"109;
%"TAP"
"6","(850,4850)","2","mstr_standard","I8";
;
CDS_LIB"mstr_standard"
BODY_TYPE"PLUMBING"
HDL_TAP"TRUE";
"B \NAC \NWC"1;
"S \NAC"
BN"14"166;
%"TAP"
"6","(-1550,2875)","2","mstr_standard","I80";
;
CDS_LIB"mstr_standard"
BODY_TYPE"PLUMBING"
HDL_TAP"TRUE";
"B \NAC \NWC"3;
"S \NAC"
BN"30"106;
%"TAP"
"6","(-1550,2825)","2","mstr_standard","I81";
;
CDS_LIB"mstr_standard"
BODY_TYPE"PLUMBING"
HDL_TAP"TRUE";
"B \NAC \NWC"3;
"S \NAC"
BN"31"105;
%"TAP"
"6","(-1550,2675)","2","mstr_standard","I82";
;
CDS_LIB"mstr_standard"
BODY_TYPE"PLUMBING"
HDL_TAP"TRUE";
"B \NAC \NWC"3;
"S \NAC"
BN"26"103;
%"TAP"
"6","(-1550,2725)","2","mstr_standard","I83";
;
CDS_LIB"mstr_standard"
BODY_TYPE"PLUMBING"
HDL_TAP"TRUE";
"B \NAC \NWC"3;
"S \NAC"
BN"29"108;
%"TAP"
"6","(-1550,2625)","2","mstr_standard","I84";
;
CDS_LIB"mstr_standard"
BODY_TYPE"PLUMBING"
HDL_TAP"TRUE";
"B \NAC \NWC"3;
"S \NAC"
BN"27"102;
%"TAP"
"6","(-1550,2525)","2","mstr_standard","I85";
;
CDS_LIB"mstr_standard"
BODY_TYPE"PLUMBING"
HDL_TAP"TRUE";
"B \NAC \NWC"3;
"S \NAC"
BN"25"101;
%"TAP"
"6","(-1550,2575)","2","mstr_standard","I86";
;
CDS_LIB"mstr_standard"
BODY_TYPE"PLUMBING"
HDL_TAP"TRUE";
"B \NAC \NWC"3;
"S \NAC"
BN"24"104;
%"TAP"
"6","(-1550,2425)","2","mstr_standard","I87";
;
CDS_LIB"mstr_standard"
BODY_TYPE"PLUMBING"
HDL_TAP"TRUE";
"B \NAC \NWC"3;
"S \NAC"
BN"23"96;
%"TAP"
"6","(-1550,2475)","2","mstr_standard","I88";
;
CDS_LIB"mstr_standard"
BODY_TYPE"PLUMBING"
HDL_TAP"TRUE";
"B \NAC \NWC"3;
"S \NAC"
BN"22"97;
%"TAP"
"6","(-1550,2375)","2","mstr_standard","I89";
;
CDS_LIB"mstr_standard"
BODY_TYPE"PLUMBING"
HDL_TAP"TRUE";
"B \NAC \NWC"3;
"S \NAC"
BN"20"95;
%"TAP"
"6","(850,4650)","2","mstr_standard","I9";
;
CDS_LIB"mstr_standard"
BODY_TYPE"PLUMBING"
HDL_TAP"TRUE";
"B \NAC \NWC"1;
"S \NAC"
BN"12"170;
%"TAP"
"6","(-1550,2325)","2","mstr_standard","I90";
;
CDS_LIB"mstr_standard"
BODY_TYPE"PLUMBING"
HDL_TAP"TRUE";
"B \NAC \NWC"3;
"S \NAC"
BN"21"100;
%"TAP"
"6","(-1550,2275)","2","mstr_standard","I91";
;
CDS_LIB"mstr_standard"
BODY_TYPE"PLUMBING"
HDL_TAP"TRUE";
"B \NAC \NWC"3;
"S \NAC"
BN"18"99;
%"TAP"
"6","(-1550,2225)","2","mstr_standard","I92";
;
CDS_LIB"mstr_standard"
BODY_TYPE"PLUMBING"
HDL_TAP"TRUE";
"B \NAC \NWC"3;
"S \NAC"
BN"19"98;
%"TAP"
"6","(-1550,2125)","2","mstr_standard","I93";
;
CDS_LIB"mstr_standard"
BODY_TYPE"PLUMBING"
HDL_TAP"TRUE";
"B \NAC \NWC"3;
"S \NAC"
BN"17"94;
%"TAP"
"6","(-1550,2175)","2","mstr_standard","I94";
;
CDS_LIB"mstr_standard"
BODY_TYPE"PLUMBING"
HDL_TAP"TRUE";
"B \NAC \NWC"3;
"S \NAC"
BN"16"92;
%"TAP"
"6","(-1550,2075)","2","mstr_standard","I95";
;
CDS_LIB"mstr_standard"
BODY_TYPE"PLUMBING"
HDL_TAP"TRUE";
"B \NAC \NWC"3;
"S \NAC"
BN"14"93;
%"TAP"
"6","(-1550,2025)","2","mstr_standard","I96";
;
CDS_LIB"mstr_standard"
BODY_TYPE"PLUMBING"
HDL_TAP"TRUE";
"B \NAC \NWC"3;
"S \NAC"
BN"15"89;
%"TAP"
"6","(-1550,1925)","2","mstr_standard","I97";
;
CDS_LIB"mstr_standard"
BODY_TYPE"PLUMBING"
HDL_TAP"TRUE";
"B \NAC \NWC"3;
"S \NAC"
BN"13"91;
%"TAP"
"6","(-1550,1975)","2","mstr_standard","I98";
;
CDS_LIB"mstr_standard"
BODY_TYPE"PLUMBING"
HDL_TAP"TRUE";
"B \NAC \NWC"3;
"S \NAC"
BN"12"88;
%"TAP"
"6","(-1550,1875)","2","mstr_standard","I99";
;
CDS_LIB"mstr_standard"
BODY_TYPE"PLUMBING"
HDL_TAP"TRUE";
"B \NAC \NWC"3;
"S \NAC"
BN"10"87;
END.
